(kicad_pcb
	(version 20260206)
	(generator "pcbnew")
	(generator_version "10.0")
	(general
		(thickness 1.6)
		(legacy_teardrops no)
	)
	(paper "A4")
	(title_block
		(title "Wiwynn_Tioga_Pass_MB.brd")
		(comment 1 "Tioga Pass / footprints 4769-4770 of 4770")
	)
	(layers
		(0 "F.Cu" signal "TOP")
		(4 "In1.Cu" signal "L2GND")
		(6 "In2.Cu" signal "L3")
		(8 "In3.Cu" signal "L4GND")
		(10 "In4.Cu" signal "L5")
		(12 "In5.Cu" signal "L6GND")
		(14 "In6.Cu" signal "L7VCC")
		(16 "In7.Cu" signal "L8VCC")
		(18 "In8.Cu" signal "L9GND")
		(20 "In9.Cu" signal "L10")
		(22 "In10.Cu" signal "L11GND")
		(24 "In11.Cu" signal "L12")
		(26 "In12.Cu" signal "L13GND")
		(2 "B.Cu" signal "BOTTOM")
		(9 "F.Adhes" user "F.Adhesive")
		(11 "B.Adhes" user "B.Adhesive")
		(13 "F.Paste" user "Package Geometry/Pastemask Top")
		(15 "B.Paste" user "Package Geometry/Pastemask Bottom")
		(5 "F.SilkS" user "Ref Des/Silkscreen Top")
		(7 "B.SilkS" user "Ref Des/Silkscreen Bottom")
		(1 "F.Mask" user "Board Geometry/Soldermask Top")
		(3 "B.Mask" user "Board Geometry/Soldermask Bottom")
		(17 "Dwgs.User" user "User.Drawings")
		(19 "Cmts.User" user "User.Comments")
		(21 "Eco1.User" user "User.Eco1")
		(23 "Eco2.User" user "User.Eco2")
		(25 "Edge.Cuts" user "Board Geometry/Outline")
		(27 "Margin" user)
		(31 "F.CrtYd" user "Package Geometry/Place Bound Top")
		(29 "B.CrtYd" user "Package Geometry/Place Bound Bottom")
		(35 "F.Fab" user "Ref Des/Assembly Top")
		(33 "B.Fab" user "Ref Des/Assembly Bottom")
	)
	(footprint ""
		(layer "B.Cu")
		(at 11.313668 -3.321812 180)
		(property "Reference" "R9U4"
			(at 0 0 0)
			(layer "B.SilkS")
			(hide yes)
			(effects
				(font
					(size 1.27 1.27)
				)
				(justify mirror)
			)
		)
		(property "Value" ""
			(at 0 0 0)
			(layer "B.Fab")
			(effects
				(font
					(size 1.27 1.27)
				)
				(justify mirror)
			)
		)
		(duplicate_pad_numbers_are_jumpers no)
		(fp_rect
			(start 0.2794 0.9906)
			(end -0.2794 -0.1016)
			(stroke
				(width 0)
				(type default)
			)
			(fill no)
			(layer "B.CrtYd")
		)
		(fp_line
			(start 0.2794 0.9906)
			(end -0.2794 0.9906)
			(stroke
				(width 0.1)
				(type default)
			)
			(layer "B.Fab")
		)
		(fp_line
			(start 0.2794 -0.1016)
			(end 0.2794 0.9906)
			(stroke
				(width 0.1)
				(type default)
			)
			(layer "B.Fab")
		)
		(fp_line
			(start -0.2794 0.9906)
			(end -0.2794 -0.1016)
			(stroke
				(width 0.1)
				(type default)
			)
			(layer "B.Fab")
		)
		(fp_line
			(start -0.2794 -0.1016)
			(end 0.2794 -0.1016)
			(stroke
				(width 0.1)
				(type default)
			)
			(layer "B.Fab")
		)
		(pad "1" smd rect
			(at 0 0)
			(size 0.508 0.508)
			(layers "B.Cu" "B.Mask" "B.Paste")
			(net "PVCCIO_CPU1")
		)
		(pad "2" smd rect
			(at 0 0.889)
			(size 0.508 0.508)
			(layers "B.Cu" "B.Mask" "B.Paste")
			(net "SVID_CLK1_CPU1_R")
		)
		(zone
			(layer "B.Cu")
			(hatch none 0.5)
			(connect_pads
				(clearance 0)
			)
			(min_thickness 0.25)
			(keepout
				(tracks not_allowed)
				(vias allowed)
				(pads allowed)
				(copperpour not_allowed)
				(footprints allowed)
			)
			(placement
				(enabled no)
				(sheetname "")
			)
			(fill
				(thermal_gap 0.5)
				(thermal_bridge_width 0.5)
				(island_removal_mode 0)
			)
			(polygon
				(pts
					(xy 11.059668 -3.956812) (xy 11.059668 -3.575812) (xy 11.567668 -3.575812) (xy 11.567668 -3.956812)
				)
			)
		)
		(zone
			(layer "B.Cu")
			(hatch none 0.5)
			(connect_pads
				(clearance 0)
			)
			(min_thickness 0.25)
			(keepout
				(tracks allowed)
				(vias not_allowed)
				(pads allowed)
				(copperpour not_allowed)
				(footprints allowed)
			)
			(placement
				(enabled no)
				(sheetname "")
			)
			(fill
				(thermal_gap 0.5)
				(thermal_bridge_width 0.5)
				(island_removal_mode 0)
			)
			(polygon
				(pts
					(xy 11.059668 -3.956812) (xy 11.059668 -3.575812) (xy 11.567668 -3.575812) (xy 11.567668 -3.956812)
				)
			)
		)
	)
	(footprint ""
		(layer "B.Cu")
		(at 365.3028 -80.0354 -90)
		(property "Reference" "R3P34"
			(at 0 0 90)
			(layer "B.SilkS")
			(hide yes)
			(effects
				(font
					(size 1.27 1.27)
				)
				(justify mirror)
			)
		)
		(property "Value" ""
			(at 0 0 90)
			(layer "B.Fab")
			(effects
				(font
					(size 1.27 1.27)
				)
				(justify mirror)
			)
		)
		(duplicate_pad_numbers_are_jumpers no)
		(fp_poly
			(pts
				(xy 0.2794 -0.1016) (xy -0.2794 -0.1016) (xy -0.2794 0.9906) (xy 0.2794 0.9906)
			)
			(stroke
				(width 0)
				(type default)
			)
			(fill no)
			(layer "B.CrtYd")
		)
		(fp_line
			(start -0.2794 0.9906)
			(end -0.2794 -0.1016)
			(stroke
				(width 0.1)
				(type default)
			)
			(layer "B.Fab")
		)
		(fp_line
			(start 0.2794 0.9906)
			(end -0.2794 0.9906)
			(stroke
				(width 0.1)
				(type default)
			)
			(layer "B.Fab")
		)
		(fp_line
			(start -0.2794 -0.1016)
			(end 0.2794 -0.1016)
			(stroke
				(width 0.1)
				(type default)
			)
			(layer "B.Fab")
		)
		(fp_line
			(start 0.2794 -0.1016)
			(end 0.2794 0.9906)
			(stroke
				(width 0.1)
				(type default)
			)
			(layer "B.Fab")
		)
		(pad "1" smd rect
			(at 0 0 90)
			(size 0.508 0.508)
			(layers "B.Cu" "B.Mask" "B.Paste")
			(net "RST_CPU0_LVC3_R1_N")
		)
		(pad "2" smd rect
			(at 0 0.889 90)
			(size 0.508 0.508)
			(layers "B.Cu" "B.Mask" "B.Paste")
			(net "RST_CPU0_LVC3_N")
		)
		(zone
			(layer "B.Cu")
			(hatch none 0.5)
			(connect_pads
				(clearance 0)
			)
			(min_thickness 0.25)
			(keepout
				(tracks not_allowed)
				(vias allowed)
				(pads allowed)
				(copperpour not_allowed)
				(footprints allowed)
			)
			(placement
				(enabled no)
				(sheetname "")
			)
			(fill
				(thermal_gap 0.5)
				(thermal_bridge_width 0.5)
				(island_removal_mode 0)
			)
			(polygon
				(pts
					(xy 364.6678 -79.7814) (xy 364.6678 -80.2894) (xy 365.0488 -80.2894) (xy 365.0488 -79.7814)
				)
			)
		)
		(zone
			(layer "B.Cu")
			(hatch none 0.5)
			(connect_pads
				(clearance 0)
			)
			(min_thickness 0.25)
			(keepout
				(tracks allowed)
				(vias not_allowed)
				(pads allowed)
				(copperpour not_allowed)
				(footprints allowed)
			)
			(placement
				(enabled no)
				(sheetname "")
			)
			(fill
				(thermal_gap 0.5)
				(thermal_bridge_width 0.5)
				(island_removal_mode 0)
			)
			(polygon
				(pts
					(xy 365.0488 -79.7814) (xy 365.0488 -80.2894) (xy 364.6678 -80.2894) (xy 364.6678 -79.7814)
				)
			)
		)
	)
)
